(kicad_pcb
	(version 20221018)
	(generator pcbnew)
	(general
    (thickness 1.586)
  )
	(paper "A4")
	(title_block
    (date "2024-03-26")
    (rev "1.1.3")
		(comment 9 "footprints 12-18 of 146")
	)
	(layers
    (0 "F.Cu" signal)
    (1 "In1.Cu" power)
    (2 "In2.Cu" power)
    (31 "B.Cu" signal)
    (32 "B.Adhes" user "B.Adhesive")
    (33 "F.Adhes" user "F.Adhesive")
    (34 "B.Paste" user)
    (35 "F.Paste" user)
    (36 "B.SilkS" user "B.Silkscreen")
    (37 "F.SilkS" user "F.Silkscreen")
    (38 "B.Mask" user)
    (39 "F.Mask" user)
    (40 "Dwgs.User" user "User.Drawings")
    (41 "Cmts.User" user "User.Comments")
    (42 "Eco1.User" user "User.Eco1")
    (43 "Eco2.User" user "User.Eco2")
    (44 "Edge.Cuts" user)
    (45 "Margin" user)
    (46 "B.CrtYd" user "B.Courtyard")
    (47 "F.CrtYd" user "F.Courtyard")
    (48 "B.Fab" user)
    (49 "F.Fab" user)
  )
	(footprint "scalenode-cm4-baseboard-footprints:R_0402_1005Metric" (layer "F.Cu")
    (at 175.959 85.186 90)
    (descr "Resistor SMD 0402")
    (tags "resistor SMD 0402")
    (property "Author" "Antmicro")
    (property "License" "Apache-2.0")
    (property "MPN" "CR0402-FX-1002GLF")
    (property "Manufacturer" "Bourns")
    (property "Sheetfile" "interfaces.kicad_sch")
    (property "Sheetname" "Interfaces")
    (property "Tolerance" "1%")
    (property "Val" "10k")
    (property "ki_description" "10k resistor in 0402 package with 1% tolerance")
    (attr smd)
    (fp_text reference "R14" (at -0.439 0.491 180) (layer "F.SilkS")
        (effects (font (size 0.7 0.7) (thickness 0.15)) (justify left bottom))
    )
    (fp_text value "R_10k_0402" (at 0 1.4 90) (layer "F.Fab")
        (effects (font (size 0.7 0.7) (thickness 0.15)) (justify left bottom))
    )
    (fp_text user "Author: Antmicro" (at -0.95 4.169 90) (layer "F.Fab") hide
        (effects (font (size 0.7 0.7) (thickness 0.15)) (justify left bottom))
    )
    (fp_text user "${REFERENCE}" (at -0.95 3.168 90) (layer "F.Fab") hide
        (effects (font (size 0.7 0.7) (thickness 0.15)) (justify left bottom))
    )
    (fp_text user "License: Apache-2.0" (at -0.95 5.169 90) (layer "F.Fab") hide
        (effects (font (size 0.7 0.7) (thickness 0.15)) (justify left bottom))
    )
    (fp_rect (start -0.95 -0.48) (end 0.95 0.48)
      (stroke (width 0.05) (type solid)) (fill none) (layer "F.CrtYd"))
    (fp_rect (start -0.5 -0.25) (end 0.5 0.25)
      (stroke (width 0.15) (type solid)) (fill none) (layer "F.Fab"))
    (pad "1" smd roundrect (at -0.485 0 90) (size 0.59 0.64) (layers "F.Cu" "F.Paste" "F.Mask") (roundrect_rratio 0.25)
      (net 250 "Net-(U1-~{OE})") (pintype "passive"))
    (pad "2" smd roundrect (at 0.485 0 90) (size 0.59 0.64) (layers "F.Cu" "F.Paste" "F.Mask") (roundrect_rratio 0.25)
      (net 11 "GND") (pintype "passive"))
  )
	(footprint "scalenode-cm4-baseboard-footprints:C_0402_1005Metric" (layer "F.Cu")
    (at 85.75 84.5 -90)
    (descr "Capacitor SMD 0402")
    (tags "capacitor SMD 0402")
    (property "Author" "Antmicro")
    (property "Dielectric" "")
    (property "License" "Apache-2.0")
    (property "MPN" "C1005X6S1A105K050BC")
    (property "Manufacturer" "TDK")
    (property "Sheetfile" "interfaces.kicad_sch")
    (property "Sheetname" "Interfaces")
    (property "Val" "1u")
    (property "Voltage" "")
    (property "ki_description" " ")
    (attr smd)
    (fp_text reference "C15" (at -1.25 -1.5 90) (layer "F.SilkS")
        (effects (font (size 0.7 0.7) (thickness 0.15)) (justify right bottom))
    )
    (fp_text value "C_1u_0402" (at 0 1.4 90) (layer "F.Fab")
        (effects (font (size 0.7 0.7) (thickness 0.15)) (justify right bottom))
    )
    (fp_text user "${REFERENCE}" (at -0.932 3.168 90) (layer "F.Fab") hide
        (effects (font (size 0.7 0.7) (thickness 0.15)) (justify right bottom))
    )
    (fp_text user "License: Apache-2.0" (at -0.932 5.17 90) (layer "F.Fab") hide
        (effects (font (size 0.7 0.7) (thickness 0.15)) (justify right bottom))
    )
    (fp_text user "Author: Antmicro" (at -0.932 4.17 90) (layer "F.Fab") hide
        (effects (font (size 0.7 0.7) (thickness 0.15)) (justify right bottom))
    )
    (fp_rect (start -0.94 -0.47) (end 0.94 0.47)
      (stroke (width 0.05) (type solid)) (fill none) (layer "F.CrtYd"))
    (fp_rect (start -0.499 -0.249) (end 0.499 0.249)
      (stroke (width 0.15) (type solid)) (fill none) (layer "F.Fab"))
    (pad "1" smd roundrect (at -0.484 0 270) (size 0.59 0.64) (layers "F.Cu" "F.Paste" "F.Mask") (roundrect_rratio 0.25)
      (net 11 "GND") (pintype "passive"))
    (pad "2" smd roundrect (at 0.484 0 270) (size 0.59 0.64) (layers "F.Cu" "F.Paste" "F.Mask") (roundrect_rratio 0.25)
      (net 232 "3V3_RPi") (pintype "passive"))
  )
	(footprint "scalenode-cm4-baseboard-footprints:MP_Pad6.2mm_Drill2.75mm" (layer "F.Cu")
    (at 200.341 93.092)
    (descr "mounting hole 2.75mm M2.5 D6.2mm PTH annular")
    (property "Author" "Antmicro")
    (property "License" "Apache-2.0")
    (property "MPN" "")
    (property "Manufacturer" "")
    (property "Sheetfile" "expansion-connectors.kicad_sch")
    (property "Sheetname" "Expansion connectors")
    (property "exclude_from_bom" "")
    (property "ki_description" "Mechanical part")
    (property "ki_keywords" "MECHANICAL")
    (attr through_hole exclude_from_pos_files exclude_from_bom)
    (fp_text reference "MP2" (at -1.091 -3.3) (layer "F.SilkS") hide
        (effects (font (size 0.7 0.7) (thickness 0.15)) (justify left bottom))
    )
    (fp_text value "MP_Pad6.2mm_Drill2.75mm" (at -11.541666 4.2) (layer "F.Fab")
        (effects (font (size 0.7 0.7) (thickness 0.15)) (justify left bottom))
    )
    (fp_text user "${REFERENCE}" (at 0 2.499) (layer "F.Fab") hide
        (effects (font (size 0.7 0.7) (thickness 0.15)) (justify left bottom))
    )
    (fp_text user "License: Apache-2.0" (at 0 4.9) (layer "F.Fab") hide
        (effects (font (size 0.7 0.7) (thickness 0.15)) (justify left bottom))
    )
    (fp_text user "Author: Antmicro" (at 0 3.7) (layer "F.Fab") hide
        (effects (font (size 0.7 0.7) (thickness 0.15)) (justify left bottom))
    )
    (pad "1" thru_hole circle (at 0 0) (size 6.2 6.2) (drill 2.75) (layers "*.Cu" "*.Mask")
      (net 234 "unconnected-(MP2-Pad1)") (pintype "passive+no_connect"))
  )
	(footprint "scalenode-cm4-baseboard-footprints:MP_Pad6.2mm_Drill2.75mm" (layer "F.Cu")
    (at 200.341 60.092)
    (descr "mounting hole 2.75mm M2.5 D6.2mm PTH annular")
    (property "Author" "Antmicro")
    (property "License" "Apache-2.0")
    (property "MPN" "")
    (property "Manufacturer" "")
    (property "Sheetfile" "expansion-connectors.kicad_sch")
    (property "Sheetname" "Expansion connectors")
    (property "exclude_from_bom" "")
    (property "ki_description" "Mechanical part")
    (property "ki_keywords" "MECHANICAL")
    (attr through_hole exclude_from_pos_files exclude_from_bom)
    (fp_text reference "MP3" (at -1.091 4.158) (layer "F.SilkS") hide
        (effects (font (size 0.7 0.7) (thickness 0.15)) (justify left bottom))
    )
    (fp_text value "MP_Pad6.2mm_Drill2.75mm" (at -11.541666 4.2) (layer "F.Fab")
        (effects (font (size 0.7 0.7) (thickness 0.15)) (justify left bottom))
    )
    (fp_text user "License: Apache-2.0" (at 0 4.9) (layer "F.Fab") hide
        (effects (font (size 0.7 0.7) (thickness 0.15)) (justify left bottom))
    )
    (fp_text user "Author: Antmicro" (at 0 3.7) (layer "F.Fab") hide
        (effects (font (size 0.7 0.7) (thickness 0.15)) (justify left bottom))
    )
    (fp_text user "${REFERENCE}" (at 0 2.499) (layer "F.Fab") hide
        (effects (font (size 0.7 0.7) (thickness 0.15)) (justify left bottom))
    )
    (pad "1" thru_hole circle (at 0 0) (size 6.2 6.2) (drill 2.75) (layers "*.Cu" "*.Mask")
      (net 245 "unconnected-(MP3-Pad1)") (pintype "passive+no_connect"))
  )
	(footprint "scalenode-cm4-baseboard-footprints:R_0402_1005Metric" (layer "F.Cu")
    (at 150.922 62.303 90)
    (descr "Resistor SMD 0402")
    (tags "resistor SMD 0402")
    (property "Author" "Antmicro")
    (property "License" "Apache-2.0")
    (property "MPN" "CR0402-FX-4700GLF")
    (property "Manufacturer" "Bourns")
    (property "Sheetfile" "compute-module.kicad_sch")
    (property "Sheetname" "Compute module")
    (property "Tolerance" "1%")
    (property "Val" "470R")
    (property "ki_description" "470R resistor in 0402 package with 1% tolerance")
    (attr smd)
    (fp_text reference "R64" (at -1.122 -0.672 90) (layer "F.SilkS")
        (effects (font (size 0.7 0.7) (thickness 0.15)) (justify left bottom))
    )
    (fp_text value "R_470R_0402" (at -2.197 -1.022 90) (layer "F.Fab")
        (effects (font (size 0.7 0.7) (thickness 0.15)) (justify left bottom))
    )
    (fp_text user "${REFERENCE}" (at -0.95 3.168 90) (layer "F.Fab") hide
        (effects (font (size 0.7 0.7) (thickness 0.15)) (justify left bottom))
    )
    (fp_text user "License: Apache-2.0" (at -0.95 5.169 90) (layer "F.Fab") hide
        (effects (font (size 0.7 0.7) (thickness 0.15)) (justify left bottom))
    )
    (fp_text user "Author: Antmicro" (at -0.95 4.169 90) (layer "F.Fab") hide
        (effects (font (size 0.7 0.7) (thickness 0.15)) (justify left bottom))
    )
    (fp_rect (start -0.95 -0.48) (end 0.95 0.48)
      (stroke (width 0.05) (type solid)) (fill none) (layer "F.CrtYd"))
    (fp_rect (start -0.5 -0.25) (end 0.5 0.25)
      (stroke (width 0.15) (type solid)) (fill none) (layer "F.Fab"))
    (pad "1" smd roundrect (at -0.485 0 90) (size 0.59 0.64) (layers "F.Cu" "F.Paste" "F.Mask") (roundrect_rratio 0.25)
      (net 244 "PROG_MODE") (pintype "passive"))
    (pad "2" smd roundrect (at 0.485 0 90) (size 0.59 0.64) (layers "F.Cu" "F.Paste" "F.Mask") (roundrect_rratio 0.25)
      (net 246 "Net-(Q6-G)") (pintype "passive"))
  )
	(footprint "scalenode-cm4-baseboard-footprints:R_0402_1005Metric" (layer "F.Cu")
    (at 152.362 61.818)
    (descr "Resistor SMD 0402")
    (tags "resistor SMD 0402")
    (property "Author" "Antmicro")
    (property "License" "Apache-2.0")
    (property "MPN" "CR0402-FX-1002GLF")
    (property "Manufacturer" "Bourns")
    (property "Sheetfile" "compute-module.kicad_sch")
    (property "Sheetname" "Compute module")
    (property "Tolerance" "1%")
    (property "Val" "10k")
    (property "ki_description" "10k resistor in 0402 package with 1% tolerance")
    (attr smd)
    (fp_text reference "R65" (at -0.962 1.382) (layer "F.SilkS")
        (effects (font (size 0.7 0.7) (thickness 0.15)) (justify left bottom))
    )
    (fp_text value "R_10k_0402" (at 0 1.4) (layer "F.Fab")
        (effects (font (size 0.7 0.7) (thickness 0.15)) (justify left bottom))
    )
    (fp_text user "${REFERENCE}" (at -0.95 3.168) (layer "F.Fab") hide
        (effects (font (size 0.7 0.7) (thickness 0.15)) (justify left bottom))
    )
    (fp_text user "License: Apache-2.0" (at -0.95 5.169) (layer "F.Fab") hide
        (effects (font (size 0.7 0.7) (thickness 0.15)) (justify left bottom))
    )
    (fp_text user "Author: Antmicro" (at -0.95 4.169) (layer "F.Fab") hide
        (effects (font (size 0.7 0.7) (thickness 0.15)) (justify left bottom))
    )
    (fp_rect (start -0.95 -0.48) (end 0.95 0.48)
      (stroke (width 0.05) (type solid)) (fill none) (layer "F.CrtYd"))
    (fp_rect (start -0.5 -0.25) (end 0.5 0.25)
      (stroke (width 0.15) (type solid)) (fill none) (layer "F.Fab"))
    (pad "1" smd roundrect (at -0.485 0) (size 0.59 0.64) (layers "F.Cu" "F.Paste" "F.Mask") (roundrect_rratio 0.25)
      (net 246 "Net-(Q6-G)") (pintype "passive"))
    (pad "2" smd roundrect (at 0.485 0) (size 0.59 0.64) (layers "F.Cu" "F.Paste" "F.Mask") (roundrect_rratio 0.25)
      (net 11 "GND") (pintype "passive"))
  )
	(footprint "scalenode-cm4-baseboard-footprints:MSOP-10_W3mm" (layer "F.Cu")
    (at 172.149 86.329 -90)
    (property "Author" "Antmicro")
    (property "License" "Apache-2.0")
    (property "MPN" "TS3USB30EDGSR")
    (property "Manufacturer" "Texas Instruments")
    (property "Sheetfile" "interfaces.kicad_sch")
    (property "Sheetname" "Interfaces")
    (attr smd)
    (fp_text reference "U1" (at -1.929 0.424) (layer "F.SilkS")
        (effects (font (size 0.7 0.7) (thickness 0.15)) (justify left bottom))
    )
    (fp_text value "TS3USB30EDGSR" (at 0 4.799 -90) (layer "F.Fab")
        (effects (font (size 0.7 0.7) (thickness 0.15)) (justify left bottom))
    )
    (fp_text user "License: Apache-2.0" (at -2.351 7.999 -90) (layer "F.Fab") hide
        (effects (font (size 0.7 0.7) (thickness 0.15)) (justify left bottom))
    )
    (fp_text user "${REFERENCE}" (at -2.351 9.198 -90) (layer "F.Fab") hide
        (effects (font (size 0.7 0.7) (thickness 0.15)) (justify left bottom))
    )
    (fp_text user "Author: Antmicro" (at -2.351 6.799 -90) (layer "F.Fab") hide
        (effects (font (size 0.7 0.7) (thickness 0.15)) (justify left bottom))
    )
    (fp_text user "REF**" (at 0 0 -90) (layer "F.Fab") hide
        (effects (font (size 0.5 0.5) (thickness 0.05)))
    )
    (fp_line (start -1.601 -1.601) (end -1.301 -1.601)
      (stroke (width 0.15) (type solid)) (layer "F.SilkS"))
    (fp_line (start -1.601 -1.301) (end -1.601 -1.601)
      (stroke (width 0.15) (type solid)) (layer "F.SilkS"))
    (fp_line (start -1.601 1.3) (end -1.301 1.6)
      (stroke (width 0.15) (type solid)) (layer "F.SilkS"))
    (fp_line (start -1.301 1.6) (end -1.301 2.797)
      (stroke (width 0.15) (type solid)) (layer "F.SilkS"))
    (fp_line (start 1.3 -1.601) (end 1.6 -1.601)
      (stroke (width 0.15) (type solid)) (layer "F.SilkS"))
    (fp_line (start 1.6 -1.601) (end 1.6 -1.301)
      (stroke (width 0.15) (type solid)) (layer "F.SilkS"))
    (fp_line (start 1.6 1.3) (end 1.6 1.6)
      (stroke (width 0.15) (type solid)) (layer "F.SilkS"))
    (fp_line (start 1.6 1.6) (end 1.3 1.6)
      (stroke (width 0.15) (type solid)) (layer "F.SilkS"))
    (fp_circle (center -1.6 1.7) (end -1.55 1.7)
      (stroke (width 0.15) (type solid)) (fill solid) (layer "F.SilkS"))
    (fp_line (start -1.75 -3.19) (end 1.71 -3.19)
      (stroke (width 0.05) (type solid)) (layer "F.CrtYd"))
    (fp_line (start -1.75 3.18) (end -1.75 -3.19)
      (stroke (width 0.05) (type solid)) (layer "F.CrtYd"))
    (fp_line (start -1.75 3.18) (end 1.71 3.18)
      (stroke (width 0.05) (type solid)) (layer "F.CrtYd"))
    (fp_line (start 1.71 -3.19) (end 1.71 3.18)
      (stroke (width 0.05) (type solid)) (layer "F.CrtYd"))
    (fp_line (start -1.45 -1.45) (end -1.45 1.1)
      (stroke (width 0.15) (type solid)) (layer "F.Fab"))
    (fp_line (start -1.45 -1.45) (end 1.449 -1.45)
      (stroke (width 0.15) (type solid)) (layer "F.Fab"))
    (fp_line (start -1.45 1.1) (end -1.101 1.449)
      (stroke (width 0.15) (type solid)) (layer "F.Fab"))
    (fp_line (start -1.101 1.449) (end 1.449 1.449)
      (stroke (width 0.15) (type solid)) (layer "F.Fab"))
    (fp_line (start 1.449 -1.45) (end 1.449 1.449)
      (stroke (width 0.15) (type solid)) (layer "F.Fab"))
    (pad "1" smd rect (at -1 2.201 270) (size 0.3 1.45) (layers "F.Cu" "F.Paste" "F.Mask")
      (net 95 "USBOTG_ID") (pinfunction "S") (pintype "input") (solder_mask_margin 0.05))
    (pad "2" smd rect (at -0.5 2.201 270) (size 0.3 1.45) (layers "F.Cu" "F.Paste" "F.Mask")
      (net 239 "Adapter_USB_P") (pinfunction "D1+") (pintype "bidirectional") (solder_mask_margin 0.05))
    (pad "3" smd rect (at 0 2.201 270) (size 0.3 1.45) (layers "F.Cu" "F.Paste" "F.Mask")
      (net 25 "/Interfaces/RPi_USB_P") (pinfunction "D2+") (pintype "bidirectional") (solder_mask_margin 0.05))
    (pad "4" smd rect (at 0.496 2.201 270) (size 0.3 1.45) (layers "F.Cu" "F.Paste" "F.Mask")
      (net 247 "Net-(U1-D+)") (pinfunction "D+") (pintype "bidirectional") (solder_mask_margin 0.05))
    (pad "5" smd rect (at 0.996 2.201 270) (size 0.3 1.45) (layers "F.Cu" "F.Paste" "F.Mask")
      (net 11 "GND") (pinfunction "GND") (pintype "power_in") (solder_mask_margin 0.05))
    (pad "6" smd rect (at 0.996 -2.202 270) (size 0.3 1.45) (layers "F.Cu" "F.Paste" "F.Mask")
      (net 248 "Net-(U1-D-)") (pinfunction "D-") (pintype "bidirectional") (solder_mask_margin 0.05))
    (pad "7" smd rect (at 0.496 -2.202 270) (size 0.3 1.45) (layers "F.Cu" "F.Paste" "F.Mask")
      (net 24 "/Interfaces/RPi_USB_N") (pinfunction "D2-") (pintype "bidirectional") (solder_mask_margin 0.05))
    (pad "8" smd rect (at 0 -2.202 270) (size 0.3 1.45) (layers "F.Cu" "F.Paste" "F.Mask")
      (net 240 "Adapter_USB_N") (pinfunction "D1-") (pintype "bidirectional") (solder_mask_margin 0.05))
    (pad "9" smd rect (at -0.5 -2.202 270) (size 0.3 1.45) (layers "F.Cu" "F.Paste" "F.Mask")
      (net 250 "Net-(U1-~{OE})") (pinfunction "~{OE}") (pintype "input") (solder_mask_margin 0.05))
    (pad "10" smd rect (at -1 -2.202 270) (size 0.3 1.45) (layers "F.Cu" "F.Paste" "F.Mask")
      (net 232 "3V3_RPi") (pinfunction "VCC") (pintype "power_in") (solder_mask_margin 0.05))
  )
)
